(kicad_pcb
	(version 20260206)
	(generator "pcbnew")
	(generator_version "10.0")
	(general
		(thickness 1.6)
		(legacy_teardrops no)
	)
	(paper "A4")
	(title_block
		(title "12092022_DA0F0TFB6D0_F0T_FAN_BOARD_MP5048_D_brd_v02_OCP.brd")
		(comment 1 "Grand Teton / footprints 68-73 of 924")
	)
	(layers
		(0 "F.Cu" signal "TOP")
		(4 "In1.Cu" signal "GND")
		(6 "In2.Cu" signal "IN1")
		(8 "In3.Cu" signal "IN2")
		(10 "In4.Cu" signal "GND1")
		(2 "B.Cu" signal "BOTTOM")
		(9 "F.Adhes" user "F.Adhesive")
		(11 "B.Adhes" user "B.Adhesive")
		(13 "F.Paste" user "Package Geometry/Pastemask Top")
		(15 "B.Paste" user "Package Geometry/Pastemask Bottom")
		(5 "F.SilkS" user "Ref Des/Silkscreen Top")
		(7 "B.SilkS" user "Ref Des/Silkscreen Bottom")
		(1 "F.Mask" user "Board Geometry/Soldermask Top")
		(3 "B.Mask" user "Board Geometry/Soldermask Bottom")
		(17 "Dwgs.User" user "User.Drawings")
		(19 "Cmts.User" user "User.Comments")
		(21 "Eco1.User" user "User.Eco1")
		(23 "Eco2.User" user "User.Eco2")
		(25 "Edge.Cuts" user "Board Geometry/Outline")
		(27 "Margin" user)
		(31 "F.CrtYd" user "Package Geometry/Place Bound Top")
		(29 "B.CrtYd" user "Package Geometry/Place Bound Bottom")
		(35 "F.Fab" user "Ref Des/Assembly Top")
		(33 "B.Fab" user "Ref Des/Assembly Bottom")
	)
	(footprint ""
		(layer "F.Cu")
		(at 9.398 -98.425 90)
		(property "Reference" "C2125"
			(at 0 0 90)
			(layer "F.SilkS")
			(hide yes)
			(effects
				(font
					(size 1.27 1.27)
				)
			)
		)
		(property "Value" ""
			(at 0 0 90)
			(layer "F.Fab")
			(effects
				(font
					(size 1.27 1.27)
				)
			)
		)
		(duplicate_pad_numbers_are_jumpers no)
		(fp_line
			(start 1.2954 -0.5842)
			(end 1.2954 0.5842)
			(stroke
				(width 0.1524)
				(type default)
			)
			(layer "F.SilkS")
		)
		(fp_line
			(start -1.2954 -0.5842)
			(end 1.2954 -0.5842)
			(stroke
				(width 0.1524)
				(type default)
			)
			(layer "F.SilkS")
		)
		(fp_line
			(start 1.2954 0.5842)
			(end -1.2954 0.5842)
			(stroke
				(width 0.1524)
				(type default)
			)
			(layer "F.SilkS")
		)
		(fp_line
			(start -1.2954 0.5842)
			(end -1.2954 -0.5842)
			(stroke
				(width 0.1524)
				(type default)
			)
			(layer "F.SilkS")
		)
		(fp_line
			(start 0.8636 -0.4572)
			(end 0.8636 -0.4064)
			(stroke
				(width 0.1)
				(type default)
			)
			(layer "F.Fab")
		)
		(fp_line
			(start -0.8636 -0.4572)
			(end 0.8636 -0.4572)
			(stroke
				(width 0.1)
				(type default)
			)
			(layer "F.Fab")
		)
		(fp_line
			(start 1.1938 -0.4064)
			(end 1.1938 0.4064)
			(stroke
				(width 0.1)
				(type default)
			)
			(layer "F.Fab")
		)
		(fp_line
			(start 0.8636 -0.4064)
			(end 1.1938 -0.4064)
			(stroke
				(width 0.1)
				(type default)
			)
			(layer "F.Fab")
		)
		(fp_line
			(start -0.8636 -0.4064)
			(end -0.8636 -0.4572)
			(stroke
				(width 0.1)
				(type default)
			)
			(layer "F.Fab")
		)
		(fp_line
			(start -1.1938 -0.4064)
			(end -0.8636 -0.4064)
			(stroke
				(width 0.1)
				(type default)
			)
			(layer "F.Fab")
		)
		(fp_line
			(start 1.1938 0.4064)
			(end 0.8636 0.4064)
			(stroke
				(width 0.1)
				(type default)
			)
			(layer "F.Fab")
		)
		(fp_line
			(start 0.8636 0.4064)
			(end 0.8636 0.4572)
			(stroke
				(width 0.1)
				(type default)
			)
			(layer "F.Fab")
		)
		(fp_line
			(start -0.8636 0.4064)
			(end -1.1938 0.4064)
			(stroke
				(width 0.1)
				(type default)
			)
			(layer "F.Fab")
		)
		(fp_line
			(start -1.1938 0.4064)
			(end -1.1938 -0.4064)
			(stroke
				(width 0.1)
				(type default)
			)
			(layer "F.Fab")
		)
		(fp_line
			(start 0.8636 0.4572)
			(end -0.8636 0.4572)
			(stroke
				(width 0.1)
				(type default)
			)
			(layer "F.Fab")
		)
		(fp_line
			(start -0.8636 0.4572)
			(end -0.8636 0.4064)
			(stroke
				(width 0.1)
				(type default)
			)
			(layer "F.Fab")
		)
		(pad "1" smd rect
			(at -0.7366 0)
			(size 0.7112 0.8128)
			(layers "F.Cu" "F.Mask" "F.Paste")
			(net "U410_D1")
		)
		(pad "2" smd rect
			(at 0.7366 0)
			(size 0.7112 0.8128)
			(layers "F.Cu" "F.Mask" "F.Paste")
			(net "GND")
		)
	)
	(footprint ""
		(layer "F.Cu")
		(at 26.924 -135.382 -90)
		(property "Reference" "R5459"
			(at 0 0 270)
			(layer "F.SilkS")
			(hide yes)
			(effects
				(font
					(size 1.27 1.27)
				)
			)
		)
		(property "Value" ""
			(at 0 0 270)
			(layer "F.Fab")
			(effects
				(font
					(size 1.27 1.27)
				)
			)
		)
		(duplicate_pad_numbers_are_jumpers no)
		(fp_line
			(start -0.7874 0.4064)
			(end -0.7874 -0.4064)
			(stroke
				(width 0.1524)
				(type default)
			)
			(layer "F.SilkS")
		)
		(fp_line
			(start 0.7874 0.4064)
			(end -0.7874 0.4064)
			(stroke
				(width 0.1524)
				(type default)
			)
			(layer "F.SilkS")
		)
		(fp_line
			(start -0.7874 -0.4064)
			(end 0.7874 -0.4064)
			(stroke
				(width 0.1524)
				(type default)
			)
			(layer "F.SilkS")
		)
		(fp_line
			(start 0.7874 -0.4064)
			(end 0.7874 0.4064)
			(stroke
				(width 0.1524)
				(type default)
			)
			(layer "F.SilkS")
		)
		(fp_line
			(start -0.67945 0.3048)
			(end -0.67945 -0.305054)
			(stroke
				(width 0.1)
				(type default)
			)
			(layer "F.Fab")
		)
		(fp_line
			(start -0.12065 0.3048)
			(end -0.67945 0.3048)
			(stroke
				(width 0.1)
				(type default)
			)
			(layer "F.Fab")
		)
		(fp_line
			(start 0.120396 0.3048)
			(end 0.120396 0.2794)
			(stroke
				(width 0.1)
				(type default)
			)
			(layer "F.Fab")
		)
		(fp_line
			(start 0.67945 0.3048)
			(end 0.120396 0.3048)
			(stroke
				(width 0.1)
				(type default)
			)
			(layer "F.Fab")
		)
		(fp_line
			(start -0.12065 0.2794)
			(end -0.12065 0.3048)
			(stroke
				(width 0.1)
				(type default)
			)
			(layer "F.Fab")
		)
		(fp_line
			(start 0.120396 0.2794)
			(end -0.12065 0.2794)
			(stroke
				(width 0.1)
				(type default)
			)
			(layer "F.Fab")
		)
		(fp_line
			(start -0.12065 -0.2794)
			(end 0.12065 -0.2794)
			(stroke
				(width 0.1)
				(type default)
			)
			(layer "F.Fab")
		)
		(fp_line
			(start 0.12065 -0.2794)
			(end 0.12065 -0.3048)
			(stroke
				(width 0.1)
				(type default)
			)
			(layer "F.Fab")
		)
		(fp_line
			(start 0.12065 -0.3048)
			(end 0.67945 -0.3048)
			(stroke
				(width 0.1)
				(type default)
			)
			(layer "F.Fab")
		)
		(fp_line
			(start 0.67945 -0.3048)
			(end 0.67945 0.3048)
			(stroke
				(width 0.1)
				(type default)
			)
			(layer "F.Fab")
		)
		(fp_line
			(start -0.67945 -0.305054)
			(end -0.12065 -0.305054)
			(stroke
				(width 0.1)
				(type default)
			)
			(layer "F.Fab")
		)
		(fp_line
			(start -0.12065 -0.305054)
			(end -0.12065 -0.2794)
			(stroke
				(width 0.1)
				(type default)
			)
			(layer "F.Fab")
		)
		(pad "1" smd circle
			(at -0.40005 0 270)
			(size 0 0)
			(layers "F.Cu" "F.Mask" "F.Paste")
			(net "SMB_PDBV_FAN_SCL")
		)
		(pad "2" smd circle
			(at 0.40005 0 270)
			(size 0 0)
			(layers "F.Cu" "F.Mask" "F.Paste")
			(net "SMB_PDBV_FAN_R_U317_SCL")
		)
	)
	(footprint ""
		(layer "F.Cu")
		(at 48.133 -179.324)
		(property "Reference" "C2082"
			(at 0 0 0)
			(layer "F.SilkS")
			(hide yes)
			(effects
				(font
					(size 1.27 1.27)
				)
			)
		)
		(property "Value" ""
			(at 0 0 0)
			(layer "F.Fab")
			(effects
				(font
					(size 1.27 1.27)
				)
			)
		)
		(duplicate_pad_numbers_are_jumpers no)
		(fp_line
			(start -0.7874 -0.4064)
			(end 0.7874 -0.4064)
			(stroke
				(width 0.1524)
				(type default)
			)
			(layer "F.SilkS")
		)
		(fp_line
			(start -0.7874 0.4064)
			(end -0.7874 -0.4064)
			(stroke
				(width 0.1524)
				(type default)
			)
			(layer "F.SilkS")
		)
		(fp_line
			(start 0.7874 -0.4064)
			(end 0.7874 0.4064)
			(stroke
				(width 0.1524)
				(type default)
			)
			(layer "F.SilkS")
		)
		(fp_line
			(start 0.7874 0.4064)
			(end -0.7874 0.4064)
			(stroke
				(width 0.1524)
				(type default)
			)
			(layer "F.SilkS")
		)
		(fp_line
			(start -0.67945 -0.305054)
			(end -0.12065 -0.305054)
			(stroke
				(width 0.1)
				(type default)
			)
			(layer "F.Fab")
		)
		(fp_line
			(start -0.67945 0.3048)
			(end -0.67945 -0.305054)
			(stroke
				(width 0.1)
				(type default)
			)
			(layer "F.Fab")
		)
		(fp_line
			(start -0.12065 -0.305054)
			(end -0.12065 -0.2794)
			(stroke
				(width 0.1)
				(type default)
			)
			(layer "F.Fab")
		)
		(fp_line
			(start -0.12065 -0.2794)
			(end 0.12065 -0.2794)
			(stroke
				(width 0.1)
				(type default)
			)
			(layer "F.Fab")
		)
		(fp_line
			(start -0.12065 0.2794)
			(end -0.12065 0.3048)
			(stroke
				(width 0.1)
				(type default)
			)
			(layer "F.Fab")
		)
		(fp_line
			(start -0.12065 0.3048)
			(end -0.67945 0.3048)
			(stroke
				(width 0.1)
				(type default)
			)
			(layer "F.Fab")
		)
		(fp_line
			(start 0.120396 0.2794)
			(end -0.12065 0.2794)
			(stroke
				(width 0.1)
				(type default)
			)
			(layer "F.Fab")
		)
		(fp_line
			(start 0.120396 0.3048)
			(end 0.120396 0.2794)
			(stroke
				(width 0.1)
				(type default)
			)
			(layer "F.Fab")
		)
		(fp_line
			(start 0.12065 -0.3048)
			(end 0.67945 -0.3048)
			(stroke
				(width 0.1)
				(type default)
			)
			(layer "F.Fab")
		)
		(fp_line
			(start 0.12065 -0.2794)
			(end 0.12065 -0.3048)
			(stroke
				(width 0.1)
				(type default)
			)
			(layer "F.Fab")
		)
		(fp_line
			(start 0.67945 -0.3048)
			(end 0.67945 0.3048)
			(stroke
				(width 0.1)
				(type default)
			)
			(layer "F.Fab")
		)
		(fp_line
			(start 0.67945 0.3048)
			(end 0.120396 0.3048)
			(stroke
				(width 0.1)
				(type default)
			)
			(layer "F.Fab")
		)
		(pad "1" smd circle
			(at -0.40005 0)
			(size 0 0)
			(layers "F.Cu" "F.Mask" "F.Paste")
			(net "P52V_FAN_3_BUFF_EN_R")
		)
		(pad "2" smd circle
			(at 0.40005 0)
			(size 0 0)
			(layers "F.Cu" "F.Mask" "F.Paste")
			(net "GND")
		)
	)
	(footprint ""
		(layer "F.Cu")
		(at 32.385 -106.68 90)
		(property "Reference" "R5393"
			(at 0 0 90)
			(layer "F.SilkS")
			(hide yes)
			(effects
				(font
					(size 1.27 1.27)
				)
			)
		)
		(property "Value" ""
			(at 0 0 90)
			(layer "F.Fab")
			(effects
				(font
					(size 1.27 1.27)
				)
			)
		)
		(duplicate_pad_numbers_are_jumpers no)
		(fp_line
			(start 0.7874 -0.4064)
			(end 0.7874 0.4064)
			(stroke
				(width 0.1524)
				(type default)
			)
			(layer "F.SilkS")
		)
		(fp_line
			(start -0.7874 -0.4064)
			(end 0.7874 -0.4064)
			(stroke
				(width 0.1524)
				(type default)
			)
			(layer "F.SilkS")
		)
		(fp_line
			(start 0.7874 0.4064)
			(end -0.7874 0.4064)
			(stroke
				(width 0.1524)
				(type default)
			)
			(layer "F.SilkS")
		)
		(fp_line
			(start -0.7874 0.4064)
			(end -0.7874 -0.4064)
			(stroke
				(width 0.1524)
				(type default)
			)
			(layer "F.SilkS")
		)
		(fp_line
			(start -0.12065 -0.305054)
			(end -0.12065 -0.2794)
			(stroke
				(width 0.1)
				(type default)
			)
			(layer "F.Fab")
		)
		(fp_line
			(start -0.67945 -0.305054)
			(end -0.12065 -0.305054)
			(stroke
				(width 0.1)
				(type default)
			)
			(layer "F.Fab")
		)
		(fp_line
			(start 0.67945 -0.3048)
			(end 0.67945 0.3048)
			(stroke
				(width 0.1)
				(type default)
			)
			(layer "F.Fab")
		)
		(fp_line
			(start 0.12065 -0.3048)
			(end 0.67945 -0.3048)
			(stroke
				(width 0.1)
				(type default)
			)
			(layer "F.Fab")
		)
		(fp_line
			(start 0.12065 -0.2794)
			(end 0.12065 -0.3048)
			(stroke
				(width 0.1)
				(type default)
			)
			(layer "F.Fab")
		)
		(fp_line
			(start -0.12065 -0.2794)
			(end 0.12065 -0.2794)
			(stroke
				(width 0.1)
				(type default)
			)
			(layer "F.Fab")
		)
		(fp_line
			(start 0.120396 0.2794)
			(end -0.12065 0.2794)
			(stroke
				(width 0.1)
				(type default)
			)
			(layer "F.Fab")
		)
		(fp_line
			(start -0.12065 0.2794)
			(end -0.12065 0.3048)
			(stroke
				(width 0.1)
				(type default)
			)
			(layer "F.Fab")
		)
		(fp_line
			(start 0.67945 0.3048)
			(end 0.120396 0.3048)
			(stroke
				(width 0.1)
				(type default)
			)
			(layer "F.Fab")
		)
		(fp_line
			(start 0.120396 0.3048)
			(end 0.120396 0.2794)
			(stroke
				(width 0.1)
				(type default)
			)
			(layer "F.Fab")
		)
		(fp_line
			(start -0.12065 0.3048)
			(end -0.67945 0.3048)
			(stroke
				(width 0.1)
				(type default)
			)
			(layer "F.Fab")
		)
		(fp_line
			(start -0.67945 0.3048)
			(end -0.67945 -0.305054)
			(stroke
				(width 0.1)
				(type default)
			)
			(layer "F.Fab")
		)
		(pad "1" smd circle
			(at -0.40005 0 90)
			(size 0 0)
			(layers "F.Cu" "F.Mask" "F.Paste")
			(net "P3V3_AUX")
		)
		(pad "2" smd circle
			(at 0.40005 0 90)
			(size 0 0)
			(layers "F.Cu" "F.Mask" "F.Paste")
			(net "FAN_2_OK_R_LED")
		)
	)
	(footprint ""
		(layer "F.Cu")
		(at 14.07795 -136.144 180)
		(property "Reference" "R5596"
			(at 0 0 180)
			(layer "F.SilkS")
			(hide yes)
			(effects
				(font
					(size 1.27 1.27)
				)
			)
		)
		(property "Value" ""
			(at 0 0 180)
			(layer "F.Fab")
			(effects
				(font
					(size 1.27 1.27)
				)
			)
		)
		(duplicate_pad_numbers_are_jumpers no)
		(fp_line
			(start 0.7874 0.4064)
			(end -0.7874 0.4064)
			(stroke
				(width 0.1524)
				(type default)
			)
			(layer "F.SilkS")
		)
		(fp_line
			(start 0.7874 -0.4064)
			(end 0.7874 0.4064)
			(stroke
				(width 0.1524)
				(type default)
			)
			(layer "F.SilkS")
		)
		(fp_line
			(start -0.7874 0.4064)
			(end -0.7874 -0.4064)
			(stroke
				(width 0.1524)
				(type default)
			)
			(layer "F.SilkS")
		)
		(fp_line
			(start -0.7874 -0.4064)
			(end 0.7874 -0.4064)
			(stroke
				(width 0.1524)
				(type default)
			)
			(layer "F.SilkS")
		)
		(fp_line
			(start 0.67945 0.3048)
			(end 0.120396 0.3048)
			(stroke
				(width 0.1)
				(type default)
			)
			(layer "F.Fab")
		)
		(fp_line
			(start 0.67945 -0.3048)
			(end 0.67945 0.3048)
			(stroke
				(width 0.1)
				(type default)
			)
			(layer "F.Fab")
		)
		(fp_line
			(start 0.12065 -0.2794)
			(end 0.12065 -0.3048)
			(stroke
				(width 0.1)
				(type default)
			)
			(layer "F.Fab")
		)
		(fp_line
			(start 0.12065 -0.3048)
			(end 0.67945 -0.3048)
			(stroke
				(width 0.1)
				(type default)
			)
			(layer "F.Fab")
		)
		(fp_line
			(start 0.120396 0.3048)
			(end 0.120396 0.2794)
			(stroke
				(width 0.1)
				(type default)
			)
			(layer "F.Fab")
		)
		(fp_line
			(start 0.120396 0.2794)
			(end -0.12065 0.2794)
			(stroke
				(width 0.1)
				(type default)
			)
			(layer "F.Fab")
		)
		(fp_line
			(start -0.12065 0.3048)
			(end -0.67945 0.3048)
			(stroke
				(width 0.1)
				(type default)
			)
			(layer "F.Fab")
		)
		(fp_line
			(start -0.12065 0.2794)
			(end -0.12065 0.3048)
			(stroke
				(width 0.1)
				(type default)
			)
			(layer "F.Fab")
		)
		(fp_line
			(start -0.12065 -0.2794)
			(end 0.12065 -0.2794)
			(stroke
				(width 0.1)
				(type default)
			)
			(layer "F.Fab")
		)
		(fp_line
			(start -0.12065 -0.305054)
			(end -0.12065 -0.2794)
			(stroke
				(width 0.1)
				(type default)
			)
			(layer "F.Fab")
		)
		(fp_line
			(start -0.67945 0.3048)
			(end -0.67945 -0.305054)
			(stroke
				(width 0.1)
				(type default)
			)
			(layer "F.Fab")
		)
		(fp_line
			(start -0.67945 -0.305054)
			(end -0.12065 -0.305054)
			(stroke
				(width 0.1)
				(type default)
			)
			(layer "F.Fab")
		)
		(pad "1" smd rect
			(at -0.40005 0)
			(size 0.4572 0.508)
			(layers "F.Cu" "F.Mask" "F.Paste")
			(net "FAN_7_TACH_OL")
		)
		(pad "2" smd rect
			(at 0.40005 0)
			(size 0.4572 0.508)
			(layers "F.Cu" "F.Mask" "F.Paste")
			(net "FAN_7_TACH_OL_R2")
		)
	)
	(footprint ""
		(layer "F.Cu")
		(at 34.29 -194.691)
		(property "Reference" "R5305"
			(at 0 0 0)
			(layer "F.SilkS")
			(hide yes)
			(effects
				(font
					(size 1.27 1.27)
				)
			)
		)
		(property "Value" ""
			(at 0 0 0)
			(layer "F.Fab")
			(effects
				(font
					(size 1.27 1.27)
				)
			)
		)
		(duplicate_pad_numbers_are_jumpers no)
		(fp_line
			(start -1.2954 -0.5842)
			(end 1.2954 -0.5842)
			(stroke
				(width 0.1524)
				(type default)
			)
			(layer "F.SilkS")
		)
		(fp_line
			(start -1.2954 0.5842)
			(end -1.2954 -0.5842)
			(stroke
				(width 0.1524)
				(type default)
			)
			(layer "F.SilkS")
		)
		(fp_line
			(start 1.2954 -0.5842)
			(end 1.2954 0.5842)
			(stroke
				(width 0.1524)
				(type default)
			)
			(layer "F.SilkS")
		)
		(fp_line
			(start 1.2954 0.5842)
			(end -1.2954 0.5842)
			(stroke
				(width 0.1524)
				(type default)
			)
			(layer "F.SilkS")
		)
		(fp_line
			(start -1.1938 -0.406654)
			(end -0.8636 -0.406654)
			(stroke
				(width 0.1)
				(type default)
			)
			(layer "F.Fab")
		)
		(fp_line
			(start -1.1938 0.4064)
			(end -1.1938 -0.406654)
			(stroke
				(width 0.1)
				(type default)
			)
			(layer "F.Fab")
		)
		(fp_line
			(start -0.8636 -0.4572)
			(end 0.8636 -0.4572)
			(stroke
				(width 0.1)
				(type default)
			)
			(layer "F.Fab")
		)
		(fp_line
			(start -0.8636 -0.406654)
			(end -0.8636 -0.4572)
			(stroke
				(width 0.1)
				(type default)
			)
			(layer "F.Fab")
		)
		(fp_line
			(start -0.8636 0.4064)
			(end -1.1938 0.4064)
			(stroke
				(width 0.1)
				(type default)
			)
			(layer "F.Fab")
		)
		(fp_line
			(start -0.8636 0.4318)
			(end -0.8636 0.4064)
			(stroke
				(width 0.1)
				(type default)
			)
			(layer "F.Fab")
		)
		(fp_line
			(start -0.8636 0.4572)
			(end -0.8636 0.4318)
			(stroke
				(width 0.1)
				(type default)
			)
			(layer "F.Fab")
		)
		(fp_line
			(start 0.8636 -0.4572)
			(end 0.8636 -0.406654)
			(stroke
				(width 0.1)
				(type default)
			)
			(layer "F.Fab")
		)
		(fp_line
			(start 0.8636 -0.406654)
			(end 1.1938 -0.406654)
			(stroke
				(width 0.1)
				(type default)
			)
			(layer "F.Fab")
		)
		(fp_line
			(start 0.8636 0.4064)
			(end 0.8636 0.4572)
			(stroke
				(width 0.1)
				(type default)
			)
			(layer "F.Fab")
		)
		(fp_line
			(start 0.8636 0.4572)
			(end -0.8636 0.4572)
			(stroke
				(width 0.1)
				(type default)
			)
			(layer "F.Fab")
		)
		(fp_line
			(start 1.1938 -0.406654)
			(end 1.1938 0.4064)
			(stroke
				(width 0.1)
				(type default)
			)
			(layer "F.Fab")
		)
		(fp_line
			(start 1.1938 0.4064)
			(end 0.8636 0.4064)
			(stroke
				(width 0.1)
				(type default)
			)
			(layer "F.Fab")
		)
		(pad "1" smd rect
			(at -0.7366 0 270)
			(size 0.7112 0.8128)
			(layers "F.Cu" "F.Mask" "F.Paste")
			(net "P52V_FAN_1")
		)
		(pad "2" smd rect
			(at 0.7366 0 270)
			(size 0.7112 0.8128)
			(layers "F.Cu" "F.Mask" "F.Paste")
			(net "FAN_1_TACH_OL_R")
		)
	)
)
